# T6G (Grand Teton) — schematic netlist excerpt (pin names and nets, part order shuffled) for the footprints in the layout excerpt that follows; sources: Cadence DE-HDL packaged netlist, KiCad conversion of 04192023_DAF0TMB3IC0_F0TG_MB_C_brd_V02_OCP.brd

PC312_5  Q_CAP  22UF 16V 20% X6S  pkg C0805  page 213 : A = SW_P12V_AUX_PVDDCR_CPU0_P1_FLT ; B = GND
PR326  Q_RES  2.2 1% CHIP  pkg 0402LF  page 225 : A = PVDD11_S3_P1_PVCC ; B = PVDD11_S3_P1_VCC1
PR87  Q_RES  2.2 1% CHIP  pkg 0402LF  page 202 : A = PVDDCR_CPU1_P0_PVCC ; B = PVDDCR_CPU1_P0_VCC4

(kicad_pcb
	(version 20260206)
	(generator "pcbnew")
	(generator_version "10.0")
	(general
		(thickness 1.6)
		(legacy_teardrops no)
	)
	(paper "A4")
	(title_block
		(title "04192023_DAF0TMB3IC0_F0TG_MB_C_brd_V02_OCP.brd")
		(comment 1 "Grand Teton / footprints 5599-5601 of 8354")
	)
	(layers
		(0 "F.Cu" signal "TOP")
		(4 "In1.Cu" signal "GND")
		(6 "In2.Cu" signal "IN1")
		(8 "In3.Cu" signal "GND1")
		(10 "In4.Cu" signal "IN2")
		(12 "In5.Cu" signal "GND2")
		(14 "In6.Cu" signal "IN3")
		(16 "In7.Cu" signal "GND3")
		(18 "In8.Cu" signal "VCC")
		(20 "In9.Cu" signal "VCC1")
		(22 "In10.Cu" signal "GND4")
		(24 "In11.Cu" signal "IN4")
		(26 "In12.Cu" signal "GND5")
		(28 "In13.Cu" signal "IN5")
		(30 "In14.Cu" signal "GND6")
		(32 "In15.Cu" signal "IN6")
		(34 "In16.Cu" signal "GND7")
		(2 "B.Cu" signal "BOTTOM")
		(9 "F.Adhes" user "F.Adhesive")
		(11 "B.Adhes" user "B.Adhesive")
		(13 "F.Paste" user "Package Geometry/Pastemask Top")
		(15 "B.Paste" user "Package Geometry/Pastemask Bottom")
		(5 "F.SilkS" user "Ref Des/Silkscreen Top")
		(7 "B.SilkS" user "Ref Des/Silkscreen Bottom")
		(1 "F.Mask" user "Board Geometry/Soldermask Top")
		(3 "B.Mask" user "Board Geometry/Soldermask Bottom")
		(17 "Dwgs.User" user "User.Drawings")
		(19 "Cmts.User" user "User.Comments")
		(21 "Eco1.User" user "User.Eco1")
		(23 "Eco2.User" user "User.Eco2")
		(25 "Edge.Cuts" user "Board Geometry/Outline")
		(27 "Margin" user)
		(31 "F.CrtYd" user "Package Geometry/Place Bound Top")
		(29 "B.CrtYd" user "Package Geometry/Place Bound Bottom")
		(35 "F.Fab" user "Ref Des/Assembly Top")
		(33 "B.Fab" user "Ref Des/Assembly Bottom")
	)
	(footprint ""
		(layer "B.Cu")
		(at 180.608986 -352.354642 -90)
		(property "Reference" "PR326"
			(at 0 0 90)
			(layer "B.SilkS")
			(hide yes)
			(effects
				(font
					(size 1.27 1.27)
				)
				(justify mirror)
			)
		)
		(property "Value" ""
			(at 0 0 90)
			(layer "B.Fab")
			(effects
				(font
					(size 1.27 1.27)
				)
				(justify mirror)
			)
		)
		(duplicate_pad_numbers_are_jumpers no)
		(fp_line
			(start -0.7874 0.4064)
			(end 0.7874 0.4064)
			(stroke
				(width 0.1524)
				(type default)
			)
			(layer "B.SilkS")
		)
		(fp_line
			(start 0.7874 0.4064)
			(end 0.7874 -0.4064)
			(stroke
				(width 0.1524)
				(type default)
			)
			(layer "B.SilkS")
		)
		(fp_line
			(start -0.7874 -0.4064)
			(end -0.7874 0.4064)
			(stroke
				(width 0.1524)
				(type default)
			)
			(layer "B.SilkS")
		)
		(fp_line
			(start 0.7874 -0.4064)
			(end -0.7874 -0.4064)
			(stroke
				(width 0.1524)
				(type default)
			)
			(layer "B.SilkS")
		)
		(fp_line
			(start -0.67945 0.3048)
			(end -0.120396 0.3048)
			(stroke
				(width 0.1)
				(type default)
			)
			(layer "B.Fab")
		)
		(fp_line
			(start -0.120396 0.3048)
			(end -0.120396 0.2794)
			(stroke
				(width 0.1)
				(type default)
			)
			(layer "B.Fab")
		)
		(fp_line
			(start 0.12065 0.3048)
			(end 0.67945 0.3048)
			(stroke
				(width 0.1)
				(type default)
			)
			(layer "B.Fab")
		)
		(fp_line
			(start 0.67945 0.3048)
			(end 0.67945 -0.305054)
			(stroke
				(width 0.1)
				(type default)
			)
			(layer "B.Fab")
		)
		(fp_line
			(start -0.120396 0.2794)
			(end 0.12065 0.2794)
			(stroke
				(width 0.1)
				(type default)
			)
			(layer "B.Fab")
		)
		(fp_line
			(start 0.12065 0.2794)
			(end 0.12065 0.3048)
			(stroke
				(width 0.1)
				(type default)
			)
			(layer "B.Fab")
		)
		(fp_line
			(start -0.12065 -0.2794)
			(end -0.12065 -0.3048)
			(stroke
				(width 0.1)
				(type default)
			)
			(layer "B.Fab")
		)
		(fp_line
			(start 0.12065 -0.2794)
			(end -0.12065 -0.2794)
			(stroke
				(width 0.1)
				(type default)
			)
			(layer "B.Fab")
		)
		(fp_line
			(start -0.67945 -0.3048)
			(end -0.67945 0.3048)
			(stroke
				(width 0.1)
				(type default)
			)
			(layer "B.Fab")
		)
		(fp_line
			(start -0.12065 -0.3048)
			(end -0.67945 -0.3048)
			(stroke
				(width 0.1)
				(type default)
			)
			(layer "B.Fab")
		)
		(fp_line
			(start 0.12065 -0.305054)
			(end 0.12065 -0.2794)
			(stroke
				(width 0.1)
				(type default)
			)
			(layer "B.Fab")
		)
		(fp_line
			(start 0.67945 -0.305054)
			(end 0.12065 -0.305054)
			(stroke
				(width 0.1)
				(type default)
			)
			(layer "B.Fab")
		)
		(pad "1" smd circle
			(at 0.40005 0 90)
			(size 0 0)
			(layers "B.Cu" "B.Mask" "B.Paste")
			(net "PVDD11_S3_P1_PVCC")
		)
		(pad "2" smd circle
			(at -0.40005 0 90)
			(size 0 0)
			(layers "B.Cu" "B.Mask" "B.Paste")
			(net "PVDD11_S3_P1_VCC1")
		)
	)
	(footprint ""
		(layer "B.Cu")
		(at 70.876668 -177.513234 -90)
		(property "Reference" "PC312_5"
			(at 0 0 90)
			(layer "B.SilkS")
			(hide yes)
			(effects
				(font
					(size 1.27 1.27)
				)
				(justify mirror)
			)
		)
		(property "Value" ""
			(at 0 0 90)
			(layer "B.Fab")
			(effects
				(font
					(size 1.27 1.27)
				)
				(justify mirror)
			)
		)
		(duplicate_pad_numbers_are_jumpers no)
		(fp_line
			(start -1.524 0.762)
			(end 1.524 0.762)
			(stroke
				(width 0.1524)
				(type default)
			)
			(layer "B.SilkS")
		)
		(fp_line
			(start 1.524 0.762)
			(end 1.524 -0.762)
			(stroke
				(width 0.1524)
				(type default)
			)
			(layer "B.SilkS")
		)
		(fp_line
			(start -1.524 -0.762)
			(end -1.524 0.762)
			(stroke
				(width 0.1524)
				(type default)
			)
			(layer "B.SilkS")
		)
		(fp_line
			(start 1.524 -0.762)
			(end -1.524 -0.762)
			(stroke
				(width 0.1524)
				(type default)
			)
			(layer "B.SilkS")
		)
		(fp_line
			(start -1.1049 0.724916)
			(end -1.1049 -0.724916)
			(stroke
				(width 0.1)
				(type default)
			)
			(layer "B.Fab")
		)
		(fp_line
			(start 1.1049 0.724916)
			(end -1.1049 0.724916)
			(stroke
				(width 0.1)
				(type default)
			)
			(layer "B.Fab")
		)
		(fp_line
			(start -1.1049 -0.724916)
			(end 1.1049 -0.724916)
			(stroke
				(width 0.1)
				(type default)
			)
			(layer "B.Fab")
		)
		(fp_line
			(start 1.1049 -0.724916)
			(end 1.1049 0.724916)
			(stroke
				(width 0.1)
				(type default)
			)
			(layer "B.Fab")
		)
		(pad "1" smd rect
			(at 0.889 0 270)
			(size 1.016 1.27)
			(layers "B.Cu" "B.Mask" "B.Paste")
			(net "SW_P12V_AUX_PVDDCR_CPU0_P1_FLT")
		)
		(pad "2" smd rect
			(at -0.889 0 270)
			(size 1.016 1.27)
			(layers "B.Cu" "B.Mask" "B.Paste")
			(net "GND")
		)
	)
	(footprint ""
		(layer "B.Cu")
		(at 306.385214 -347.77553 -90)
		(property "Reference" "PR87"
			(at 0 0 90)
			(layer "B.SilkS")
			(hide yes)
			(effects
				(font
					(size 1.27 1.27)
				)
				(justify mirror)
			)
		)
		(property "Value" ""
			(at 0 0 90)
			(layer "B.Fab")
			(effects
				(font
					(size 1.27 1.27)
				)
				(justify mirror)
			)
		)
		(duplicate_pad_numbers_are_jumpers no)
		(fp_line
			(start -0.7874 0.4064)
			(end 0.7874 0.4064)
			(stroke
				(width 0.1524)
				(type default)
			)
			(layer "B.SilkS")
		)
		(fp_line
			(start 0.7874 0.4064)
			(end 0.7874 -0.4064)
			(stroke
				(width 0.1524)
				(type default)
			)
			(layer "B.SilkS")
		)
		(fp_line
			(start -0.7874 -0.4064)
			(end -0.7874 0.4064)
			(stroke
				(width 0.1524)
				(type default)
			)
			(layer "B.SilkS")
		)
		(fp_line
			(start 0.7874 -0.4064)
			(end -0.7874 -0.4064)
			(stroke
				(width 0.1524)
				(type default)
			)
			(layer "B.SilkS")
		)
		(fp_line
			(start -0.67945 0.3048)
			(end -0.120396 0.3048)
			(stroke
				(width 0.1)
				(type default)
			)
			(layer "B.Fab")
		)
		(fp_line
			(start -0.120396 0.3048)
			(end -0.120396 0.2794)
			(stroke
				(width 0.1)
				(type default)
			)
			(layer "B.Fab")
		)
		(fp_line
			(start 0.12065 0.3048)
			(end 0.67945 0.3048)
			(stroke
				(width 0.1)
				(type default)
			)
			(layer "B.Fab")
		)
		(fp_line
			(start 0.67945 0.3048)
			(end 0.67945 -0.305054)
			(stroke
				(width 0.1)
				(type default)
			)
			(layer "B.Fab")
		)
		(fp_line
			(start -0.120396 0.2794)
			(end 0.12065 0.2794)
			(stroke
				(width 0.1)
				(type default)
			)
			(layer "B.Fab")
		)
		(fp_line
			(start 0.12065 0.2794)
			(end 0.12065 0.3048)
			(stroke
				(width 0.1)
				(type default)
			)
			(layer "B.Fab")
		)
		(fp_line
			(start -0.12065 -0.2794)
			(end -0.12065 -0.3048)
			(stroke
				(width 0.1)
				(type default)
			)
			(layer "B.Fab")
		)
		(fp_line
			(start 0.12065 -0.2794)
			(end -0.12065 -0.2794)
			(stroke
				(width 0.1)
				(type default)
			)
			(layer "B.Fab")
		)
		(fp_line
			(start -0.67945 -0.3048)
			(end -0.67945 0.3048)
			(stroke
				(width 0.1)
				(type default)
			)
			(layer "B.Fab")
		)
		(fp_line
			(start -0.12065 -0.3048)
			(end -0.67945 -0.3048)
			(stroke
				(width 0.1)
				(type default)
			)
			(layer "B.Fab")
		)
		(fp_line
			(start 0.12065 -0.305054)
			(end 0.12065 -0.2794)
			(stroke
				(width 0.1)
				(type default)
			)
			(layer "B.Fab")
		)
		(fp_line
			(start 0.67945 -0.305054)
			(end 0.12065 -0.305054)
			(stroke
				(width 0.1)
				(type default)
			)
			(layer "B.Fab")
		)
		(pad "1" smd circle
			(at 0.40005 0 90)
			(size 0 0)
			(layers "B.Cu" "B.Mask" "B.Paste")
			(net "PVDDCR_CPU1_P0_PVCC")
		)
		(pad "2" smd circle
			(at -0.40005 0 90)
			(size 0 0)
			(layers "B.Cu" "B.Mask" "B.Paste")
			(net "PVDDCR_CPU1_P0_VCC4")
		)
	)
)
